# S9S_MB_2U (Grand Teton) — schematic parts with pin connectivity, parts 5593–5747 of 6093; source: Cadence DE-HDL packaged netlist (pstxprt.dat, pstxnet.dat, pstchip.dat)

R4517  Q_RES  10K 1% CHIP  pkg 0402LF  page 206 : 1 = P3V3 ; 2 = OCP_SFF_CLK_OE_N
R4518  Q_RES  10K 1% CHIP  pkg 0402LF  page 211 : 1 = P3V3 ; 2 = CLK_GPU_2_OE_N
R4519  Q_RES  10K 1% CHIP  pkg 0402LF  page 211 : 1 = P3V3 ; 2 = CLK_GPU_1_OE_N
R4520  Q_RES  10K 1% CHIP  pkg 0402LF  page 211 : 1 = P3V3 ; 2 = CLK_SWB_BUF2_OE_N
R4521  Q_RES  10K 1% CHIP  pkg 0402LF  page 212 : 1 = P3V3_AUX ; 2 = CLK_GEN2_BMC_RC_OE_N
R4530  Q_RES  33.2 1% CHIP  pkg 0402LF  page 241 : 1 = SMB_SML1_PMBUS_HSC_SCL_R3 ; 2 = SMB_SML1_PMBUS_HSC_SCL
R4531  Q_RES  0 5% CHIP  pkg 0402LF  page 241 : 1 = SMB_SML1_PMBUS_HSC_SDA_R3 ; 2 = SMB_SML1_PMBUS_HSC_SDA
R4532  Q_RES  10K 1% CHIP  pkg 0402LF  page 157 : 1 = P3V3_AUX ; 2 = HP_LVC3_OCP_V3_1_P12V_PWRGD
R4533  Q_RES  2K 1% EMPTY  pkg 0402LF  page 219 : 1 = PWRGD_DRAMPWRGD_CPU1_GH_R_LVC1 ; 2 = GND
R4534  Q_RES  0 5% CHIP  pkg 0402LF  page 206 : 1 = CLK_SWB_OE_N ; 2 = FM_DB2000_8_OE_N
R4535  Q_RES  10 1% CHIP  pkg 0402LF  page 240 : 1 = CLK_100M_BMC_P3E_DP ; 2 = CLK_100M_BMC_P3E_DP_R
R4536  Q_RES  10 1% CHIP  pkg 0402LF  page 240 : 1 = CLK_100M_BMC_P3E_DN ; 2 = CLK_100M_BMC_P3E_DN_R
R4537  Q_RES  0 5% CHIP  pkg 0402LF  page 166 : 1 = FM_P2E_EN_N ; 2 = CLK_GEN2_GPU_FPGA_OE_OR_N
R4540  Q_RES  33.2 1% CHIP  pkg 0402LF  page 237 : 1 = SMB_HOST_CLK_BUF_ISO_3V3AUX_S_1 ; 2 = SMB_HOST_CLK_BUF_ISO_3V3AUX_SCL
R4541  Q_RES  33.2 1% CHIP  pkg 0402LF  page 237 : 1 = SMB_HOST_CLK_BUF_ISO_3V3AUX_S_2 ; 2 = SMB_HOST_CLK_BUF_ISO_3V3AUX_SDA
R4543  Q_RES  4.7K 5% CHIP  pkg 0402LF  page 145 : 1 = P3V3_AUX ; 2 = HGX_DETECT_N
R4544  Q_RES  100K 1% EMPTY  pkg 0402LF  page 145 : 1 = HGX_DETECT_N ; 2 = GND
R4545  Q_RES  4.7K 5% CHIP  pkg 0402LF  page 145 : 1 = P3V3_AUX ; 2 = HGX_DETECT
R4546  Q_RES  4.7K 5% EMPTY  pkg 0402LF  page 145 : 1 = P3V3_AUX ; 2 = HGX_DETECT_N_ISO
R4547  Q_RES  100K 1% EMPTY  pkg 0402LF  page 145 : 1 = P3V3_AUX ; 2 = SWB_HSC_EN
R4548  Q_RES  100K 1% CHIP  pkg 0402LF  page 145 : 1 = SWB_HSC_EN ; 2 = GND
R4549  Q_RES  4.7K 5% EMPTY  pkg 0402LF  page 145 : 1 = P3V3_AUX ; 2 = SWB_HSC_EN_BUF_R
R4550  Q_RES  49.9 1% CHIP  pkg 0402LF  page 145 : 1 = SWB_HSC_EN_BUF_R ; 2 = SWB_HSC_EN_BUF
R4551  Q_RES  54.9K 1% EMPTY  pkg 0402LF  page 246 : 1 = P3V3_AUX ; 2 = HPDB_HSC_PWRGD
R4552  Q_RES  100K 1% CHIP  pkg 0402LF  page 246 : 1 = HPDB_HSC_PWRGD ; 2 = GND
R4553  Q_RES  4.7K 5% CHIP  pkg 0402LF  page 246 : 1 = P3V3_AUX ; 2 = HPDB_HSC_PWRGD_N
R4554  Q_RES  4.7K 5% CHIP  pkg 0402LF  page 246 : 1 = P3V3_AUX ; 2 = HPDB_HSC_PWRGD_ISO
R4555  Q_RES  4.7K 5% EMPTY  pkg 0402LF  page 145 : 1 = SWB_HSC_EN_BUF_R ; 2 = GND
R4556  Q_RES  33.2 1% CHIP  pkg 0402LF  page 215 : 1 = HGX_DETECT_N_R ; 2 = HGX_DETECT_N
R4557  Q_RES  33.2 1% CHIP  pkg 0402LF  page 215 : 1 = HPDB_HSC_PWRGD_ISO ; 2 = HPDB_HSC_PWRGD_ISO_R
R4558  Q_RES  33.2 1% CHIP  pkg 0402LF  page 215 : 1 = SWB_HSC_EN ; 2 = SWB_HSC_EN_R
R4559  Q_RES  100K 1% CHIP  pkg 0402LF  page 146 : 1 = SWB_HSC_PWRGD ; 2 = GND
R4560  Q_RES  4.7K 5% CHIP  pkg 0402LF  page 146 : 1 = P3V3_AUX ; 2 = SWB_HSC_PWRGD_N
R4561  Q_RES  4.7K 5% CHIP  pkg 0402LF  page 146 : 1 = P3V3_AUX ; 2 = SWB_HSC_PWRGD_ISO
R4562  Q_RES  100K 1% EMPTY  pkg 0402LF  page 146 : 1 = P3V3_AUX ; 2 = SWB_HSC_PWRGD
R4563  Q_RES  33.2 1% CHIP  pkg 0402LF  page 215 : 1 = SWB_HSC_PWRGD_ISO_R ; 2 = SWB_HSC_PWRGD_ISO
R4564  Q_RES  10K 1% CHIP  pkg 0402LF  page 184 : 1 = PD_GPP_I_14 ; 2 = GND
R4565  Q_RES  10K 1% CHIP  pkg 0402LF  page 184 : 1 = PD_GPP_I_13 ; 2 = GND
R4567  Q_RES  5.11K 1% CHIP  pkg 0402LF  page 250 : 1 = P3V3_PDB_AUX_ADC ; 2 = P1V581_PDB_ADC
R4568  Q_RES  4.7K 1% CHIP  pkg 0402LF  page 250 : 1 = P1V581_PDB_ADC ; 2 = GND
R4569  Q_RES  0 5% EMPTY  pkg 0402LF  page 145 : 1 = GPU_3V3IO_RSVD1 ; 2 = GPU_3V3IO_RSVD1_ISO
R4570  Q_RES  0 5% EMPTY  pkg 0402LF  page 145 : 1 = GPU_3V3IO_RSVD3 ; 2 = GPU_3V3IO_RSVD3_ISO
R4571  Q_RES  0 5% EMPTY  pkg 0402LF  page 145 : 1 = GPU_3V3IO_RSVD4 ; 2 = GPU_3V3IO_RSVD4_ISO
R4572  Q_RES  0 5% EMPTY  pkg 0402LF  page 146 : 1 = GPU_3V3IO_RSVD1_FFU ; 2 = GPU_3V3IO_RSVD1_FFU_ISO
R4573  Q_RES  0 5% EMPTY  pkg 0402LF  page 146 : 1 = PRSNT_CABLE_GPU_B3_N ; 2 = PRSNT_CABLE_GPU_B3_ISO_N
R4574  Q_RES  0 5% EMPTY  pkg 0402LF  page 146 : 1 = PRSNT_CABLE_GPU_A1_N ; 2 = PRSNT_CABLE_GPU_A1_ISO_N
R4575  Q_RES  0 5% EMPTY  pkg 0402LF  page 146 : 1 = GPU_3V3IO_RSVD0_FFU ; 2 = GPU_3V3IO_RSVD0_FFU_ISO
R4576  Q_RES  0 5% EMPTY  pkg 0402LF  page 146 : 1 = GPU_3V3IO_RSVD5_FFU ; 2 = GPU_3V3IO_RSVD5_FFU_ISO
R4577  Q_RES  0 5% EMPTY  pkg 0402LF  page 146 : 1 = GPU_3V3IO_RSVD3_FFU ; 2 = GPU_3V3IO_RSVD3_FFU_ISO
R4578  Q_RES  0 5% EMPTY  pkg 0402LF  page 146 : 1 = PRSNT_CABLE_GPU_A2_N ; 2 = PRSNT_CABLE_GPU_A2_ISO_N
R4579  Q_RES  10K 1% CHIP  pkg 0402LF  page 195 : 1 = P3V3_AUX ; 2 = FAB_BMC_REV_ID0
R4580  Q_RES  10K 1% EMPTY  pkg 0402LF  page 195 : 1 = P3V3_AUX ; 2 = FM_BOARD_BMC_SKU_ID4
R4581  Q_RES  1K 1% CHIP  pkg 0402LF  page 195 : 1 = FM_BOARD_BMC_SKU_ID4 ; 2 = GND
R4582  Q_RES  10K 1% EMPTY  pkg 0402LF  page 195 : 1 = P3V3_AUX ; 2 = FM_BOARD_BMC_SKU_ID1
R4583  Q_RES  1K 1% CHIP  pkg 0402LF  page 195 : 1 = FM_BOARD_BMC_SKU_ID1 ; 2 = GND
R4584  Q_RES  10K 1% EMPTY  pkg 0402LF  page 195 : 1 = P3V3_AUX ; 2 = FM_BOARD_BMC_SKU_ID0
R4585  Q_RES  1K 1% CHIP  pkg 0402LF  page 195 : 1 = FM_BOARD_BMC_SKU_ID0 ; 2 = GND
R4586  Q_RES  10K 1% CHIP  pkg 0402LF  page 195 : 1 = P3V3_AUX ; 2 = FAB_BMC_REV_ID2
R4588  Q_RES  1K 1% EMPTY  pkg 0402LF  page 195 : 1 = FAB_BMC_REV_ID2 ; 2 = GND
R4589  Q_RES  10K 1% CHIP  pkg 0402LF  page 195 : 1 = P3V3_AUX ; 2 = FAB_BMC_REV_ID1
R4590  Q_RES  1K 1% EMPTY  pkg 0402LF  page 195 : 1 = FAB_BMC_REV_ID1 ; 2 = GND
R4591  Q_RES  10K 1% EMPTY  pkg 0402LF  page 195 : 1 = P3V3_AUX ; 2 = FM_BOARD_BMC_SKU_ID3
R4592  Q_RES  1K 1% CHIP  pkg 0402LF  page 195 : 1 = FM_BOARD_BMC_SKU_ID3 ; 2 = GND
R4593  Q_RES  0 5% CHIP  pkg 0402LF  page 266 : 1 = IRQ_PVCCIN_CPU0_VRHOT_R_N ; 2 = IRQ_PVCCIN_CPU0_VRHOT_N
R4594  Q_RES  0 5% CHIP  pkg 0402LF  page 292 : 1 = SMB_VR_3V3AUX_SCL_R ; 2 = SMB_CLK_PVCCINFAON_CPU1
R4595  Q_RES  0 5% CHIP  pkg 0402LF  page 296 : 1 = SMB_VR_3V3AUX_SCL_R ; 2 = SMB_CLK_PVCCD_HV_CPU1
R4596  Q_RES  1K 1% EMPTY  pkg 0402LF  page 195 : 1 = FAB_BMC_REV_ID0 ; 2 = GND
R4597  Q_RES  10K 1% EMPTY  pkg 0402LF  page 195 : 1 = P3V3_AUX ; 2 = FM_BOARD_BMC_SKU_ID2
R4598  Q_RES  1K 1% CHIP  pkg 0402LF  page 195 : 1 = FM_BOARD_BMC_SKU_ID2 ; 2 = GND
R4599  Q_RES  0 5% CHIP  pkg 0402LF  page 214 : 1 = HP_LVC3_OCP_V3_2_P12V_PWRGD ; 2 = HP_LVC3_OCP_V3_2_HSC_PWRGD_PLD_
R4600  Q_RES  0 5% CHIP  pkg 0402LF  page 214 : 1 = HP_LVC3_OCP_V3_1_P12V_PWRGD ; 2 = HP_LVC3_OCP_V3_1_HSC_PWRGD_PLD_
R4601  Q_RES  0 5% CHIP  pkg 0402LF  page 155 : 1 = CLK_50M_NCSI_OCP_SFF_ISO ; 2 = CLK_50M_NCSI_OCP_SFF_ISO_R
R4602  Q_RES  0 5% CHIP  pkg 0402LF  page 161 : 1 = CLK_50M_NCSI_OCP_V3_2_ISO ; 2 = CLK_50M_NCSI_OCP_V3_2_ISO_R
R4603  Q_RES  10K 1% CHIP  pkg 0402LF  page 234 : 1 = SMB_BMC_GPU_EN ; 2 = GND
R4604  Q_RES  4.7K 5% CHIP  pkg 0402LF  page 224 : 1 = P3V3_AUX ; 2 = PWRGD_PS_PWROK_PLD_N
R4605  Q_RES  4.7K 5% CHIP  pkg 0402LF  page 224 : 1 = P3V3_AUX ; 2 = PWRGD_PS_PWROK_PLD_ISO
R4606  Q_RES  0 5% CHIP  pkg 0402LF  page 214 : 1 = E1S_0_LED_ACT_R_N ; 2 = E1S_0_LED_ACT_N
R4607  Q_RES  0 5% CHIP  pkg 0402LF  page 214 : 1 = LED_HDD_ACTIVITY_B_N ; 2 = LED_HDD_ACTIVITY_B_PLD_N
R4608  Q_RES  33.2 1% CHIP  pkg 0402LF  page 214 : 1 = GPU_FPGA_RST_N ; 2 = GPU_FPGA_RST_R_N
R4609  Q_RES  33.2 1% CHIP  pkg 0402LF  page 214 : 1 = FM_JTAG_TCK_MUX_SEL_R ; 2 = FM_JTAG_TCK_MUX_SEL
R4610  Q_RES  33.2 1% CHIP  pkg 0402LF  page 214 : 1 = CLK_GEN2_GPU_FPGA_OE_R_N ; 2 = CLK_GEN2_GPU_FPGA_OE_N
R4611  Q_RES  33.2 1% CHIP  pkg 0402LF  page 214 : 1 = FM_BMC_CPU_FBRK_OUT_R_N ; 2 = FM_BMC_CPU_FBRK_OUT_N
R4612  Q_RES  33.2 1% CHIP  pkg 0402LF  page 214 : 1 = FM_PCH_SPKR ; 2 = FM_PCH_SPKR_R
R4613  Q_RES  0 5% EMPTY  pkg 0402LF  page 158 : 1 = OCP_V3_1_P3V3_PWRGD ; 2 = HP_OCP_V3_1_RST_R
R4614  Q_RES  33.2 1% CHIP  pkg 0402LF  page 158 : 1 = HP_OCP_V3_1_RST ; 2 = HP_OCP_V3_1_RST_R
R4615  Q_RES  0 5% EMPTY  pkg 0402LF  page 164 : 1 = OCP_V3_2_P3V3_PWRGD ; 2 = HP_OCP_V3_2_RST_R
R4616  Q_RES  33.2 1% CHIP  pkg 0402LF  page 164 : 1 = HP_OCP_V3_2_RST ; 2 = HP_OCP_V3_2_RST_R
R4617  Q_RES  33.2 1% CHIP  pkg 0402LF  page 164 : 1 = HP_LVC3_OCP_V3_2_PWRGD ; 2 = HP_LVC3_OCP_V3_2_PWRGD_R
R4618  Q_RES  33.2 1% CHIP  pkg 0402LF  page 158 : 1 = HP_LVC3_OCP_V3_1_PWRGD ; 2 = HP_LVC3_OCP_V3_1_PWRGD_R
R4620  Q_RES  4.7K 5% CHIP  pkg 0402LF  page 306 : 1 = P3V3_AUX ; 2 = IRQ_UV_DETECT_N
R4621  Q_RES  33.2 1% CHIP  pkg 0402LF  page 226 : 1 = H_CPU_CATERR_LVC2_BMC_R_N ; 2 = H_CPU_CATERR_LVC2_BMC_N
R4622  Q_RES  2K 1% CHIP  pkg 0402LF  page 219 : 1 = RST_PERST_SWB_N ; 2 = GND
R4623  Q_RES  1K 1% CHIP  pkg 0402LF  page 248 : 1 = P3V3_AUX ; 2 = PU_JTAG_SW_PU
R4624  Q_RES  0 5% CHIP  pkg 0402LF  page 248 : 1 = JTAG_BMC_SW_OE ; 2 = JTAG_BMC_SW_R_OE
R4625  Q_RES  100 1% CHIP  pkg 0402LF  page 213 : 1 = JTAG_BMC_SW_OE ; 2 = JTAG_BMC_SW_PLD_OE
R4626  Q_RES  0 5% CHIP  pkg 0402LF  page 248 : 1 = JTAG_BMC_TDO ; 2 = JTAG_BMC_TDO_R
R4627  Q_RES  0 5% CHIP  pkg 0402LF  page 248 : 1 = JTAG_BMC_TDI ; 2 = JTAG_BMC_TDI_R
R4628  Q_RES  0 5% CHIP  pkg 0402LF  page 248 : 1 = JTAG_BMC_TMS ; 2 = JTAG_BMC_TMS_R
R4629  Q_RES  0 5% CHIP  pkg 0402LF  page 248 : 1 = JTAG_BMC_TCK ; 2 = JTAG_BMC_TCK_R
R4630  Q_RES  0 5% CHIP  pkg 0402LF  page 248 : 1 = JTAG_BMC_SW_TDO_R ; 2 = JTAG_BMC_SW_TDO
R4631  Q_RES  0 5% CHIP  pkg 0402LF  page 248 : 1 = JTAG_BMC_SW_TDI_R ; 2 = JTAG_BMC_SW_TDI
R4632  Q_RES  0 5% CHIP  pkg 0402LF  page 248 : 1 = JTAG_BMC_SW_TMS_R ; 2 = JTAG_BMC_SW_TMS
R4633  Q_RES  0 5% CHIP  pkg 0402LF  page 248 : 1 = JTAG_BMC_SW_TCK_R ; 2 = JTAG_BMC_SW_TCK
R4634  Q_RES  1K 1% EMPTY  pkg 0402LF  page 248 : 1 = P3V3_AUX ; 2 = JTAG_BMC_SW_OE
R4635  Q_RES  10K 1% CHIP  pkg 0402LF  page 248 : 1 = JTAG_BMC_SW_OE ; 2 = GND
R4636  Q_RES  200K 1% CHIP  pkg 0402LF  page 169 : 1 = USB3_PCH_RX_DP<4> ; 2 = GND
R4637  Q_RES  200K 1% CHIP  pkg 0402LF  page 169 : 1 = USB3_PCH_RX_DN<4> ; 2 = GND
R4638  Q_RES  243 1% CHIP  pkg 1206LF  page 260 : 1 = P5V ; 2 = VR_P5V_EN_D
R4639  Q_RES  243 1% CHIP  pkg 1206LF  page 260 : 1 = P5V ; 2 = VR_P5V_EN_D
R4640  Q_RES  243 1% CHIP  pkg 1206LF  page 260 : 1 = P5V ; 2 = VR_P5V_EN_D
R4641  Q_RES  243 1% CHIP  pkg 1206LF  page 260 : 1 = P5V ; 2 = VR_P5V_EN_D
R4642  Q_RES  1K 1% EMPTY  pkg 0402LF  page 167 : 1 = P3V3_AUX ; 2 = FM_P2E_BUF2_VODB_DB
R4643  Q_RES  1K 1% EMPTY  pkg 0402LF  page 167 : 1 = P3V3_AUX ; 2 = FM_P2E_BUF2_VODA_DB
R4644  Q_RES  1K 1% EMPTY  pkg 0402LF  page 167 : 1 = P3V3_AUX ; 2 = FM_P2E_BUF2_EQB1
R4645  Q_RES  1K 1% EMPTY  pkg 0402LF  page 167 : 1 = P3V3_AUX ; 2 = FM_P2E_BUF2_EQB0
R4646  Q_RES  1K 1% EMPTY  pkg 0402LF  page 167 : 1 = FM_P2E_BUF2_EQB0 ; 2 = GND
R4647  Q_RES  1K 1% CHIP  pkg 0402LF  page 167 : 1 = FM_P2E_BUF2_VODA_DB ; 2 = GND
R4648  Q_RES  1K 1% EMPTY  pkg 0402LF  page 167 : 1 = P3V3_AUX ; 2 = FM_P2E_BUF2_EQA1
R4649  Q_RES  1K 1% EMPTY  pkg 0402LF  page 167 : 1 = P3V3_AUX ; 2 = FM_P2E_BUF2_EQA0
R4650  Q_RES  1K 1% EMPTY  pkg 0402LF  page 167 : 1 = FM_P2E_BUF2_EQA0 ; 2 = GND
R4651  Q_RES  0 5% CHIP  pkg 0402LF  page 167 : 1 = FM_P2E_EN2_N ; 2 = CLK_GEN2_GPU_FPGA_OE_OR_N
R4652  Q_RES  0 5% EMPTY  pkg 0402LF  page 306 : 1 = A_HSC_LOW_DRAIN ; 2 = HSC_D_OC
R4653  Q_RES  1K 1% CHIP  pkg 0402LF  page 167 : 1 = FM_P2E_BUF2_VODB_DB ; 2 = GND
R4654  Q_RES  1K 1% CHIP  pkg 0402LF  page 167 : 1 = FM_P2E_BUF2_EQA1 ; 2 = GND
R4655  Q_RES  1K 1% EMPTY  pkg 0402LF  page 167 : 1 = P3V3_AUX ; 2 = FM_P2E_BUF2_RXDET
R4656  Q_RES  1K 1% CHIP  pkg 0402LF  page 167 : 1 = P3V3_AUX ; 2 = FM_P2E_BUF2_SD_TH
R4657  Q_RES  1K 1% EMPTY  pkg 0402LF  page 167 : 1 = FM_P2E_BUF2_SD_TH ; 2 = GND
R4658  Q_RES  1K 1% EMPTY  pkg 0402LF  page 167 : 1 = FM_P2E_BUF2_VOD_SEL ; 2 = GND
R4659  Q_RES  0 5% CHIP  pkg 0402LF  page 167 : 1 = P2E_MB_BMC_TX_C_DP<0> ; 2 = P2E_MB_BMC_TX_C_R1_DP<0>
R4660  Q_RES  0 5% CHIP  pkg 0402LF  page 167 : 1 = P2E_MB_BMC_TX_C_DN<0> ; 2 = P2E_MB_BMC_TX_C_R1_DN<0>
R4661  Q_RES  0 5% EMPTY  pkg 0402LF  page 167 : 1 = P2E_MB_BMC_TX_C_DP<0> ; 2 = P2E_MB_BMC_TX_C_R2_DP<0>
R4662  Q_RES  0 5% EMPTY  pkg 0402LF  page 167 : 1 = P2E_MB_BMC_TX_C_DN<0> ; 2 = P2E_MB_BMC_TX_C_R2_DN<0>
R4663  Q_RES  0 5% CHIP  pkg 0402LF  page 167 : 1 = P2E_MB_BMC_RX_DP<0> ; 2 = P2E_MB_BMC_RX_R1_DP<0>
R4664  Q_RES  0 5% CHIP  pkg 0402LF  page 167 : 1 = P2E_MB_BMC_RX_DN<0> ; 2 = P2E_MB_BMC_RX_R1_DN<0>
R4665  Q_RES  0 5% EMPTY  pkg 0402LF  page 167 : 1 = P2E_MB_BMC_RX_DP<0> ; 2 = P2E_MB_BMC_RX_R2_DP<0>
R4666  Q_RES  0 5% EMPTY  pkg 0402LF  page 167 : 1 = P2E_MB_BMC_RX_DN<0> ; 2 = P2E_MB_BMC_RX_R2_DN<0>
R4667  Q_RES  160K 1% EMPTY  pkg 0402LF  page 306 : 1 = HSC_CSOUT ; 2 = A_HSC_LOW
R4668  Q_RES  10K 1% EMPTY  pkg 0402LF  page 306 : 1 = A_HSC_LOW ; 2 = GND
R4669  Q_RES  160K 1% EMPTY  pkg 0402LF  page 306 : 1 = HSC_CSOUT ; 2 = A_HSC_HIGH
R4670  Q_RES  10K 1% EMPTY  pkg 0402LF  page 306 : 1 = A_HSC_HIGH ; 2 = GND
R4671  Q_RES  10K 1% EMPTY  pkg 0402LF  page 306 : 1 = P3V3_AUX ; 2 = HSC_D_OC
R4672  Q_RES  10K 1% EMPTY  pkg 0402LF  page 306 : 1 = P3V3_AUX ; 2 = A_HSC_LOW_GATE
R4673  Q_RES  0 5% EMPTY  pkg 0402LF  page 306 : 1 = A_HSC_LOW_GATE ; 2 = GND
R4674  Q_RES  10K 1% CHIP  pkg 0402LF  page 220 : 1 = FM_SLP_SUS_RSM_RST_N ; 2 = GND
R4677  Q_RES  33.2 1% CHIP  pkg 0402LF  page 260 : 1 = PWRGD_P3V3_R1 ; 2 = PWRGD_P3V3
R4678  Q_RES  1K 1% CHIP  pkg 0402LF  page 260 : 1 = PWRGD_P5V_ISO_R ; 2 = PWRGD_P5V_ISO
R4679  Q_RES  10K 1% CHIP  pkg 0402LF  page 260 : 1 = P5V ; 2 = PWRGD_P5V
R4680  Q_RES  100K 1% CHIP  pkg 0402LF  page 260 : 1 = P12V_AUX ; 2 = PWRGD_P5V_N
R4681  Q_RES  100K 1% CHIP  pkg 0402LF  page 260 : 1 = PWRGD_P3V3_R1 ; 2 = GND
R4682  Q_RES  100K 1% CHIP  pkg 0402LF  page 260 : 1 = PWRGD_P5V ; 2 = GND
R4684  Q_RES  0 5% EMPTY  pkg 0402LF  page 305 : 1 = P12V_HSC_TEMP_ALERT_N ; 2 = P12V_HSC_TEMP_ALERT_R_N
R4685  Q_RES  10.5K 1% EMPTY  pkg 0402LF  page 305 : 1 = P3V3_AUX ; 2 = P12V_HSC_TEMP_ALERT_R_N
R4686  Q_RES  10.5K 1% EMPTY  pkg 0402LF  page 305 : 1 = P3V3_AUX ; 2 = P12V_HSC_T_CRIT_R_N
R4687  Q_RES  4.7K 1% EMPTY  pkg 0402LF  page 251 : 1 = GND ; 2 = HSC_TYPE_ADC_A1
R4688  Q_RES  4.7K 1% EMPTY  pkg 0402LF  page 251 : 1 = GND ; 2 = HSC_TYPE_ADC_A0
